(kicad_pcb
	(version 20260206)
	(generator "pcbnew")
	(generator_version "10.0")
	(general
		(thickness 1.6)
		(legacy_teardrops no)
	)
	(paper "A4")
	(title_block
		(title "12092022_DA0F0TFB6D0_F0T_FAN_BOARD_MP5048_D_brd_v02_OCP.brd")
		(comment 1 "Grand Teton / footprints 222-228 of 924")
	)
	(layers
		(0 "F.Cu" signal "TOP")
		(4 "In1.Cu" signal "GND")
		(6 "In2.Cu" signal "IN1")
		(8 "In3.Cu" signal "IN2")
		(10 "In4.Cu" signal "GND1")
		(2 "B.Cu" signal "BOTTOM")
		(9 "F.Adhes" user "F.Adhesive")
		(11 "B.Adhes" user "B.Adhesive")
		(13 "F.Paste" user "Package Geometry/Pastemask Top")
		(15 "B.Paste" user "Package Geometry/Pastemask Bottom")
		(5 "F.SilkS" user "Ref Des/Silkscreen Top")
		(7 "B.SilkS" user "Ref Des/Silkscreen Bottom")
		(1 "F.Mask" user "Board Geometry/Soldermask Top")
		(3 "B.Mask" user "Board Geometry/Soldermask Bottom")
		(17 "Dwgs.User" user "User.Drawings")
		(19 "Cmts.User" user "User.Comments")
		(21 "Eco1.User" user "User.Eco1")
		(23 "Eco2.User" user "User.Eco2")
		(25 "Edge.Cuts" user "Board Geometry/Outline")
		(27 "Margin" user)
		(31 "F.CrtYd" user "Package Geometry/Place Bound Top")
		(29 "B.CrtYd" user "Package Geometry/Place Bound Bottom")
		(35 "F.Fab" user "Ref Des/Assembly Top")
		(33 "B.Fab" user "Ref Des/Assembly Bottom")
	)
	(footprint ""
		(layer "F.Cu")
		(at 4.318 -251.714 -90)
		(property "Reference" "R5422"
			(at 0 0 270)
			(layer "F.SilkS")
			(hide yes)
			(effects
				(font
					(size 1.27 1.27)
				)
			)
		)
		(property "Value" ""
			(at 0 0 270)
			(layer "F.Fab")
			(effects
				(font
					(size 1.27 1.27)
				)
			)
		)
		(duplicate_pad_numbers_are_jumpers no)
		(fp_line
			(start -0.7874 0.4064)
			(end -0.7874 -0.4064)
			(stroke
				(width 0.1524)
				(type default)
			)
			(layer "F.SilkS")
		)
		(fp_line
			(start 0.7874 0.4064)
			(end -0.7874 0.4064)
			(stroke
				(width 0.1524)
				(type default)
			)
			(layer "F.SilkS")
		)
		(fp_line
			(start -0.7874 -0.4064)
			(end 0.7874 -0.4064)
			(stroke
				(width 0.1524)
				(type default)
			)
			(layer "F.SilkS")
		)
		(fp_line
			(start 0.7874 -0.4064)
			(end 0.7874 0.4064)
			(stroke
				(width 0.1524)
				(type default)
			)
			(layer "F.SilkS")
		)
		(fp_line
			(start -0.67945 0.3048)
			(end -0.67945 -0.305054)
			(stroke
				(width 0.1)
				(type default)
			)
			(layer "F.Fab")
		)
		(fp_line
			(start -0.12065 0.3048)
			(end -0.67945 0.3048)
			(stroke
				(width 0.1)
				(type default)
			)
			(layer "F.Fab")
		)
		(fp_line
			(start 0.120396 0.3048)
			(end 0.120396 0.2794)
			(stroke
				(width 0.1)
				(type default)
			)
			(layer "F.Fab")
		)
		(fp_line
			(start 0.67945 0.3048)
			(end 0.120396 0.3048)
			(stroke
				(width 0.1)
				(type default)
			)
			(layer "F.Fab")
		)
		(fp_line
			(start -0.12065 0.2794)
			(end -0.12065 0.3048)
			(stroke
				(width 0.1)
				(type default)
			)
			(layer "F.Fab")
		)
		(fp_line
			(start 0.120396 0.2794)
			(end -0.12065 0.2794)
			(stroke
				(width 0.1)
				(type default)
			)
			(layer "F.Fab")
		)
		(fp_line
			(start -0.12065 -0.2794)
			(end 0.12065 -0.2794)
			(stroke
				(width 0.1)
				(type default)
			)
			(layer "F.Fab")
		)
		(fp_line
			(start 0.12065 -0.2794)
			(end 0.12065 -0.3048)
			(stroke
				(width 0.1)
				(type default)
			)
			(layer "F.Fab")
		)
		(fp_line
			(start 0.12065 -0.3048)
			(end 0.67945 -0.3048)
			(stroke
				(width 0.1)
				(type default)
			)
			(layer "F.Fab")
		)
		(fp_line
			(start 0.67945 -0.3048)
			(end 0.67945 0.3048)
			(stroke
				(width 0.1)
				(type default)
			)
			(layer "F.Fab")
		)
		(fp_line
			(start -0.67945 -0.305054)
			(end -0.12065 -0.305054)
			(stroke
				(width 0.1)
				(type default)
			)
			(layer "F.Fab")
		)
		(fp_line
			(start -0.12065 -0.305054)
			(end -0.12065 -0.2794)
			(stroke
				(width 0.1)
				(type default)
			)
			(layer "F.Fab")
		)
		(pad "1" smd circle
			(at -0.40005 0 270)
			(size 0 0)
			(layers "F.Cu" "F.Mask" "F.Paste")
			(net "FAN_6_PRESENT_R")
		)
		(pad "2" smd circle
			(at 0.40005 0 270)
			(size 0 0)
			(layers "F.Cu" "F.Mask" "F.Paste")
			(net "FAN_6_PRESENT")
		)
	)
	(footprint ""
		(layer "F.Cu")
		(at 14.859 -127.127)
		(property "Reference" "R5613"
			(at 0 0 0)
			(layer "F.SilkS")
			(hide yes)
			(effects
				(font
					(size 1.27 1.27)
				)
			)
		)
		(property "Value" ""
			(at 0 0 0)
			(layer "F.Fab")
			(effects
				(font
					(size 1.27 1.27)
				)
			)
		)
		(duplicate_pad_numbers_are_jumpers no)
		(fp_line
			(start -0.7874 -0.4064)
			(end 0.7874 -0.4064)
			(stroke
				(width 0.1524)
				(type default)
			)
			(layer "F.SilkS")
		)
		(fp_line
			(start -0.7874 0.4064)
			(end -0.7874 -0.4064)
			(stroke
				(width 0.1524)
				(type default)
			)
			(layer "F.SilkS")
		)
		(fp_line
			(start 0.7874 -0.4064)
			(end 0.7874 0.4064)
			(stroke
				(width 0.1524)
				(type default)
			)
			(layer "F.SilkS")
		)
		(fp_line
			(start 0.7874 0.4064)
			(end -0.7874 0.4064)
			(stroke
				(width 0.1524)
				(type default)
			)
			(layer "F.SilkS")
		)
		(fp_line
			(start -0.67945 -0.305054)
			(end -0.12065 -0.305054)
			(stroke
				(width 0.1)
				(type default)
			)
			(layer "F.Fab")
		)
		(fp_line
			(start -0.67945 0.3048)
			(end -0.67945 -0.305054)
			(stroke
				(width 0.1)
				(type default)
			)
			(layer "F.Fab")
		)
		(fp_line
			(start -0.12065 -0.305054)
			(end -0.12065 -0.2794)
			(stroke
				(width 0.1)
				(type default)
			)
			(layer "F.Fab")
		)
		(fp_line
			(start -0.12065 -0.2794)
			(end 0.12065 -0.2794)
			(stroke
				(width 0.1)
				(type default)
			)
			(layer "F.Fab")
		)
		(fp_line
			(start -0.12065 0.2794)
			(end -0.12065 0.3048)
			(stroke
				(width 0.1)
				(type default)
			)
			(layer "F.Fab")
		)
		(fp_line
			(start -0.12065 0.3048)
			(end -0.67945 0.3048)
			(stroke
				(width 0.1)
				(type default)
			)
			(layer "F.Fab")
		)
		(fp_line
			(start 0.120396 0.2794)
			(end -0.12065 0.2794)
			(stroke
				(width 0.1)
				(type default)
			)
			(layer "F.Fab")
		)
		(fp_line
			(start 0.120396 0.3048)
			(end 0.120396 0.2794)
			(stroke
				(width 0.1)
				(type default)
			)
			(layer "F.Fab")
		)
		(fp_line
			(start 0.12065 -0.3048)
			(end 0.67945 -0.3048)
			(stroke
				(width 0.1)
				(type default)
			)
			(layer "F.Fab")
		)
		(fp_line
			(start 0.12065 -0.2794)
			(end 0.12065 -0.3048)
			(stroke
				(width 0.1)
				(type default)
			)
			(layer "F.Fab")
		)
		(fp_line
			(start 0.67945 -0.3048)
			(end 0.67945 0.3048)
			(stroke
				(width 0.1)
				(type default)
			)
			(layer "F.Fab")
		)
		(fp_line
			(start 0.67945 0.3048)
			(end 0.120396 0.3048)
			(stroke
				(width 0.1)
				(type default)
			)
			(layer "F.Fab")
		)
		(pad "1" smd rect
			(at -0.40005 0 180)
			(size 0.4572 0.508)
			(layers "F.Cu" "F.Mask" "F.Paste")
			(net "FAN_5_PWM")
		)
		(pad "2" smd rect
			(at 0.40005 0 180)
			(size 0.4572 0.508)
			(layers "F.Cu" "F.Mask" "F.Paste")
			(net "FAN_5_PWM_R1")
		)
	)
	(footprint ""
		(layer "F.Cu")
		(at 38.6461 -131.318)
		(property "Reference" "R5578"
			(at 0 0 0)
			(layer "F.SilkS")
			(hide yes)
			(effects
				(font
					(size 1.27 1.27)
				)
			)
		)
		(property "Value" ""
			(at 0 0 0)
			(layer "F.Fab")
			(effects
				(font
					(size 1.27 1.27)
				)
			)
		)
		(duplicate_pad_numbers_are_jumpers no)
		(fp_line
			(start -0.7874 -0.4064)
			(end 0.7874 -0.4064)
			(stroke
				(width 0.1524)
				(type default)
			)
			(layer "F.SilkS")
		)
		(fp_line
			(start -0.7874 0.4064)
			(end -0.7874 -0.4064)
			(stroke
				(width 0.1524)
				(type default)
			)
			(layer "F.SilkS")
		)
		(fp_line
			(start 0.7874 -0.4064)
			(end 0.7874 0.4064)
			(stroke
				(width 0.1524)
				(type default)
			)
			(layer "F.SilkS")
		)
		(fp_line
			(start 0.7874 0.4064)
			(end -0.7874 0.4064)
			(stroke
				(width 0.1524)
				(type default)
			)
			(layer "F.SilkS")
		)
		(fp_line
			(start -0.67945 -0.305054)
			(end -0.12065 -0.305054)
			(stroke
				(width 0.1)
				(type default)
			)
			(layer "F.Fab")
		)
		(fp_line
			(start -0.67945 0.3048)
			(end -0.67945 -0.305054)
			(stroke
				(width 0.1)
				(type default)
			)
			(layer "F.Fab")
		)
		(fp_line
			(start -0.12065 -0.305054)
			(end -0.12065 -0.2794)
			(stroke
				(width 0.1)
				(type default)
			)
			(layer "F.Fab")
		)
		(fp_line
			(start -0.12065 -0.2794)
			(end 0.12065 -0.2794)
			(stroke
				(width 0.1)
				(type default)
			)
			(layer "F.Fab")
		)
		(fp_line
			(start -0.12065 0.2794)
			(end -0.12065 0.3048)
			(stroke
				(width 0.1)
				(type default)
			)
			(layer "F.Fab")
		)
		(fp_line
			(start -0.12065 0.3048)
			(end -0.67945 0.3048)
			(stroke
				(width 0.1)
				(type default)
			)
			(layer "F.Fab")
		)
		(fp_line
			(start 0.120396 0.2794)
			(end -0.12065 0.2794)
			(stroke
				(width 0.1)
				(type default)
			)
			(layer "F.Fab")
		)
		(fp_line
			(start 0.120396 0.3048)
			(end 0.120396 0.2794)
			(stroke
				(width 0.1)
				(type default)
			)
			(layer "F.Fab")
		)
		(fp_line
			(start 0.12065 -0.3048)
			(end 0.67945 -0.3048)
			(stroke
				(width 0.1)
				(type default)
			)
			(layer "F.Fab")
		)
		(fp_line
			(start 0.12065 -0.2794)
			(end 0.12065 -0.3048)
			(stroke
				(width 0.1)
				(type default)
			)
			(layer "F.Fab")
		)
		(fp_line
			(start 0.67945 -0.3048)
			(end 0.67945 0.3048)
			(stroke
				(width 0.1)
				(type default)
			)
			(layer "F.Fab")
		)
		(fp_line
			(start 0.67945 0.3048)
			(end 0.120396 0.3048)
			(stroke
				(width 0.1)
				(type default)
			)
			(layer "F.Fab")
		)
		(pad "1" smd rect
			(at -0.40005 0 180)
			(size 0.4572 0.508)
			(layers "F.Cu" "F.Mask" "F.Paste")
			(net "FAN_1_TACH_OL")
		)
		(pad "2" smd rect
			(at 0.40005 0 180)
			(size 0.4572 0.508)
			(layers "F.Cu" "F.Mask" "F.Paste")
			(net "FAN_1_TACH_OL_R2")
		)
	)
	(footprint ""
		(layer "F.Cu")
		(at 33.782 -166.751)
		(property "Reference" "C2010"
			(at 0 0 0)
			(layer "F.SilkS")
			(hide yes)
			(effects
				(font
					(size 1.27 1.27)
				)
			)
		)
		(property "Value" ""
			(at 0 0 0)
			(layer "F.Fab")
			(effects
				(font
					(size 1.27 1.27)
				)
			)
		)
		(duplicate_pad_numbers_are_jumpers no)
		(fp_line
			(start -0.7874 -0.4064)
			(end 0.7874 -0.4064)
			(stroke
				(width 0.1524)
				(type default)
			)
			(layer "F.SilkS")
		)
		(fp_line
			(start -0.7874 0.4064)
			(end -0.7874 -0.4064)
			(stroke
				(width 0.1524)
				(type default)
			)
			(layer "F.SilkS")
		)
		(fp_line
			(start 0.7874 -0.4064)
			(end 0.7874 0.4064)
			(stroke
				(width 0.1524)
				(type default)
			)
			(layer "F.SilkS")
		)
		(fp_line
			(start 0.7874 0.4064)
			(end -0.7874 0.4064)
			(stroke
				(width 0.1524)
				(type default)
			)
			(layer "F.SilkS")
		)
		(fp_line
			(start -0.67945 -0.305054)
			(end -0.12065 -0.305054)
			(stroke
				(width 0.1)
				(type default)
			)
			(layer "F.Fab")
		)
		(fp_line
			(start -0.67945 0.3048)
			(end -0.67945 -0.305054)
			(stroke
				(width 0.1)
				(type default)
			)
			(layer "F.Fab")
		)
		(fp_line
			(start -0.12065 -0.305054)
			(end -0.12065 -0.2794)
			(stroke
				(width 0.1)
				(type default)
			)
			(layer "F.Fab")
		)
		(fp_line
			(start -0.12065 -0.2794)
			(end 0.12065 -0.2794)
			(stroke
				(width 0.1)
				(type default)
			)
			(layer "F.Fab")
		)
		(fp_line
			(start -0.12065 0.2794)
			(end -0.12065 0.3048)
			(stroke
				(width 0.1)
				(type default)
			)
			(layer "F.Fab")
		)
		(fp_line
			(start -0.12065 0.3048)
			(end -0.67945 0.3048)
			(stroke
				(width 0.1)
				(type default)
			)
			(layer "F.Fab")
		)
		(fp_line
			(start 0.120396 0.2794)
			(end -0.12065 0.2794)
			(stroke
				(width 0.1)
				(type default)
			)
			(layer "F.Fab")
		)
		(fp_line
			(start 0.120396 0.3048)
			(end 0.120396 0.2794)
			(stroke
				(width 0.1)
				(type default)
			)
			(layer "F.Fab")
		)
		(fp_line
			(start 0.12065 -0.3048)
			(end 0.67945 -0.3048)
			(stroke
				(width 0.1)
				(type default)
			)
			(layer "F.Fab")
		)
		(fp_line
			(start 0.12065 -0.2794)
			(end 0.12065 -0.3048)
			(stroke
				(width 0.1)
				(type default)
			)
			(layer "F.Fab")
		)
		(fp_line
			(start 0.67945 -0.3048)
			(end 0.67945 0.3048)
			(stroke
				(width 0.1)
				(type default)
			)
			(layer "F.Fab")
		)
		(fp_line
			(start 0.67945 0.3048)
			(end 0.120396 0.3048)
			(stroke
				(width 0.1)
				(type default)
			)
			(layer "F.Fab")
		)
		(pad "1" smd circle
			(at -0.40005 0)
			(size 0 0)
			(layers "F.Cu" "F.Mask" "F.Paste")
			(net "P3V3_AUX")
		)
		(pad "2" smd circle
			(at 0.40005 0)
			(size 0 0)
			(layers "F.Cu" "F.Mask" "F.Paste")
			(net "GND")
		)
	)
	(footprint ""
		(layer "F.Cu")
		(at 37.82695 -137.668 180)
		(property "Reference" "R5597"
			(at 0 0 180)
			(layer "F.SilkS")
			(hide yes)
			(effects
				(font
					(size 1.27 1.27)
				)
			)
		)
		(property "Value" ""
			(at 0 0 180)
			(layer "F.Fab")
			(effects
				(font
					(size 1.27 1.27)
				)
			)
		)
		(duplicate_pad_numbers_are_jumpers no)
		(fp_line
			(start 0.7874 0.4064)
			(end -0.7874 0.4064)
			(stroke
				(width 0.1524)
				(type default)
			)
			(layer "F.SilkS")
		)
		(fp_line
			(start 0.7874 -0.4064)
			(end 0.7874 0.4064)
			(stroke
				(width 0.1524)
				(type default)
			)
			(layer "F.SilkS")
		)
		(fp_line
			(start -0.7874 0.4064)
			(end -0.7874 -0.4064)
			(stroke
				(width 0.1524)
				(type default)
			)
			(layer "F.SilkS")
		)
		(fp_line
			(start -0.7874 -0.4064)
			(end 0.7874 -0.4064)
			(stroke
				(width 0.1524)
				(type default)
			)
			(layer "F.SilkS")
		)
		(fp_line
			(start 0.67945 0.3048)
			(end 0.120396 0.3048)
			(stroke
				(width 0.1)
				(type default)
			)
			(layer "F.Fab")
		)
		(fp_line
			(start 0.67945 -0.3048)
			(end 0.67945 0.3048)
			(stroke
				(width 0.1)
				(type default)
			)
			(layer "F.Fab")
		)
		(fp_line
			(start 0.12065 -0.2794)
			(end 0.12065 -0.3048)
			(stroke
				(width 0.1)
				(type default)
			)
			(layer "F.Fab")
		)
		(fp_line
			(start 0.12065 -0.3048)
			(end 0.67945 -0.3048)
			(stroke
				(width 0.1)
				(type default)
			)
			(layer "F.Fab")
		)
		(fp_line
			(start 0.120396 0.3048)
			(end 0.120396 0.2794)
			(stroke
				(width 0.1)
				(type default)
			)
			(layer "F.Fab")
		)
		(fp_line
			(start 0.120396 0.2794)
			(end -0.12065 0.2794)
			(stroke
				(width 0.1)
				(type default)
			)
			(layer "F.Fab")
		)
		(fp_line
			(start -0.12065 0.3048)
			(end -0.67945 0.3048)
			(stroke
				(width 0.1)
				(type default)
			)
			(layer "F.Fab")
		)
		(fp_line
			(start -0.12065 0.2794)
			(end -0.12065 0.3048)
			(stroke
				(width 0.1)
				(type default)
			)
			(layer "F.Fab")
		)
		(fp_line
			(start -0.12065 -0.2794)
			(end 0.12065 -0.2794)
			(stroke
				(width 0.1)
				(type default)
			)
			(layer "F.Fab")
		)
		(fp_line
			(start -0.12065 -0.305054)
			(end -0.12065 -0.2794)
			(stroke
				(width 0.1)
				(type default)
			)
			(layer "F.Fab")
		)
		(fp_line
			(start -0.67945 0.3048)
			(end -0.67945 -0.305054)
			(stroke
				(width 0.1)
				(type default)
			)
			(layer "F.Fab")
		)
		(fp_line
			(start -0.67945 -0.305054)
			(end -0.12065 -0.305054)
			(stroke
				(width 0.1)
				(type default)
			)
			(layer "F.Fab")
		)
		(pad "1" smd rect
			(at -0.40005 0)
			(size 0.4572 0.508)
			(layers "F.Cu" "F.Mask" "F.Paste")
			(net "FAN_0_PWM")
		)
		(pad "2" smd rect
			(at 0.40005 0)
			(size 0.4572 0.508)
			(layers "F.Cu" "F.Mask" "F.Paste")
			(net "FAN_0_PWM_R1")
		)
	)
	(footprint ""
		(layer "F.Cu")
		(at 15.621 -170.815)
		(property "Reference" "C1942"
			(at 0 0 0)
			(layer "F.SilkS")
			(hide yes)
			(effects
				(font
					(size 1.27 1.27)
				)
			)
		)
		(property "Value" ""
			(at 0 0 0)
			(layer "F.Fab")
			(effects
				(font
					(size 1.27 1.27)
				)
			)
		)
		(duplicate_pad_numbers_are_jumpers no)
		(fp_line
			(start -0.7874 -0.4064)
			(end 0.7874 -0.4064)
			(stroke
				(width 0.1524)
				(type default)
			)
			(layer "F.SilkS")
		)
		(fp_line
			(start -0.7874 0.4064)
			(end -0.7874 -0.4064)
			(stroke
				(width 0.1524)
				(type default)
			)
			(layer "F.SilkS")
		)
		(fp_line
			(start 0.7874 -0.4064)
			(end 0.7874 0.4064)
			(stroke
				(width 0.1524)
				(type default)
			)
			(layer "F.SilkS")
		)
		(fp_line
			(start 0.7874 0.4064)
			(end -0.7874 0.4064)
			(stroke
				(width 0.1524)
				(type default)
			)
			(layer "F.SilkS")
		)
		(fp_line
			(start -0.67945 -0.305054)
			(end -0.12065 -0.305054)
			(stroke
				(width 0.1)
				(type default)
			)
			(layer "F.Fab")
		)
		(fp_line
			(start -0.67945 0.3048)
			(end -0.67945 -0.305054)
			(stroke
				(width 0.1)
				(type default)
			)
			(layer "F.Fab")
		)
		(fp_line
			(start -0.12065 -0.305054)
			(end -0.12065 -0.2794)
			(stroke
				(width 0.1)
				(type default)
			)
			(layer "F.Fab")
		)
		(fp_line
			(start -0.12065 -0.2794)
			(end 0.12065 -0.2794)
			(stroke
				(width 0.1)
				(type default)
			)
			(layer "F.Fab")
		)
		(fp_line
			(start -0.12065 0.2794)
			(end -0.12065 0.3048)
			(stroke
				(width 0.1)
				(type default)
			)
			(layer "F.Fab")
		)
		(fp_line
			(start -0.12065 0.3048)
			(end -0.67945 0.3048)
			(stroke
				(width 0.1)
				(type default)
			)
			(layer "F.Fab")
		)
		(fp_line
			(start 0.120396 0.2794)
			(end -0.12065 0.2794)
			(stroke
				(width 0.1)
				(type default)
			)
			(layer "F.Fab")
		)
		(fp_line
			(start 0.120396 0.3048)
			(end 0.120396 0.2794)
			(stroke
				(width 0.1)
				(type default)
			)
			(layer "F.Fab")
		)
		(fp_line
			(start 0.12065 -0.3048)
			(end 0.67945 -0.3048)
			(stroke
				(width 0.1)
				(type default)
			)
			(layer "F.Fab")
		)
		(fp_line
			(start 0.12065 -0.2794)
			(end 0.12065 -0.3048)
			(stroke
				(width 0.1)
				(type default)
			)
			(layer "F.Fab")
		)
		(fp_line
			(start 0.67945 -0.3048)
			(end 0.67945 0.3048)
			(stroke
				(width 0.1)
				(type default)
			)
			(layer "F.Fab")
		)
		(fp_line
			(start 0.67945 0.3048)
			(end 0.120396 0.3048)
			(stroke
				(width 0.1)
				(type default)
			)
			(layer "F.Fab")
		)
		(pad "1" smd circle
			(at -0.40005 0)
			(size 0 0)
			(layers "F.Cu" "F.Mask" "F.Paste")
			(net "FAN_5_PRESENT_N")
		)
		(pad "2" smd circle
			(at 0.40005 0)
			(size 0 0)
			(layers "F.Cu" "F.Mask" "F.Paste")
			(net "GND")
		)
	)
	(footprint ""
		(layer "F.Cu")
		(at 25.850088 -51.90998)
		(property "Reference" "H1"
			(at -3.9878 -4.435348 0)
			(unlocked yes)
			(layer "F.SilkS")
			(effects
				(font
					(size 0.7874 0.5842)
					(thickness 0.1524)
				)
				(justify left)
			)
		)
		(property "Value" ""
			(at 0 0 0)
			(layer "F.Fab")
			(effects
				(font
					(size 1.27 1.27)
				)
			)
		)
		(duplicate_pad_numbers_are_jumpers no)
		(pad "1" thru_hole oval
			(at 0 0)
			(size 9.017 21.0058)
			(drill 3.0226
				(offset 0 5.999988)
			)
			(layers "*.Cu" "*.Mask")
			(remove_unused_layers no)
			(net "GND")
			(clearance -1.500378)
			(padstack
				(mode front_inner_back)
				(layer "Inner"
					(shape circle)
					(size 0 0)
					(clearance 0)
				)
				(layer "B.Cu"
					(shape oval)
					(size 9.017 21.0058)
					(offset 0 5.999988)
					(clearance -1.500378)
				)
			)
		)
	)
)
